(kicad_pcb
	(version 20260206)
	(generator "pcbnew")
	(generator_version "10.0")
	(general
		(thickness 1.6)
		(legacy_teardrops no)
	)
	(paper "A4")
	(title_block
		(title "Bryce Canyon_IOM_IOC_16318-2_OCP.brd")
		(comment 1 "Bryce Canyon / footprints 324-330 of 1605")
	)
	(layers
		(0 "F.Cu" signal "TOP")
		(4 "In1.Cu" signal "L2GND")
		(6 "In2.Cu" signal "L3")
		(8 "In3.Cu" signal "L4VCC")
		(10 "In4.Cu" signal "L5VCC")
		(12 "In5.Cu" signal "L6")
		(14 "In6.Cu" signal "L7GND")
		(2 "B.Cu" signal "BOTTOM")
		(9 "F.Adhes" user "F.Adhesive")
		(11 "B.Adhes" user "B.Adhesive")
		(13 "F.Paste" user "Package Geometry/Pastemask Top")
		(15 "B.Paste" user "Package Geometry/Pastemask Bottom")
		(5 "F.SilkS" user "Ref Des/Silkscreen Top")
		(7 "B.SilkS" user "Ref Des/Silkscreen Bottom")
		(1 "F.Mask" user "Board Geometry/Soldermask Top")
		(3 "B.Mask" user "Board Geometry/Soldermask Bottom")
		(17 "Dwgs.User" user "User.Drawings")
		(19 "Cmts.User" user "User.Comments")
		(21 "Eco1.User" user "User.Eco1")
		(23 "Eco2.User" user "User.Eco2")
		(25 "Edge.Cuts" user "Board Geometry/Outline")
		(27 "Margin" user)
		(31 "F.CrtYd" user "Package Geometry/Place Bound Top")
		(29 "B.CrtYd" user "Package Geometry/Place Bound Bottom")
		(35 "F.Fab" user "Ref Des/Assembly Top")
		(33 "B.Fab" user "Ref Des/Assembly Bottom")
	)
	(footprint ""
		(layer "F.Cu")
		(at 30.873446 -176.033938 180)
		(property "Reference" "R497"
			(at 0 0 180)
			(layer "F.SilkS")
			(hide yes)
			(effects
				(font
					(size 1.27 1.27)
				)
			)
		)
		(property "Value" "619KR2F-GP"
			(at 0.064008 -3.993896 180)
			(unlocked yes)
			(layer "F.Fab")
			(hide yes)
			(effects
				(font
					(size 1.016 1.016)
					(thickness 0.1524)
				)
			)
		)
		(property "Device Type" "R402H16"
			(at 0.064008 -5.517896 180)
			(unlocked yes)
			(layer "F.Fab")
			(hide yes)
			(effects
				(font
					(size 1.016 1.016)
					(thickness 0.1524)
				)
			)
		)
		(duplicate_pad_numbers_are_jumpers no)
		(fp_line
			(start 0.508 -0.9398)
			(end -0.508 -0.9398)
			(stroke
				(width 0.1524)
				(type default)
			)
			(layer "F.SilkS")
		)
		(fp_line
			(start -0.508 -0.9398)
			(end -0.508 0.9398)
			(stroke
				(width 0.1524)
				(type default)
			)
			(layer "F.SilkS")
		)
		(fp_rect
			(start -0.508 0.9398)
			(end 0.508 -0.9398)
			(stroke
				(width 0)
				(type default)
			)
			(fill no)
			(layer "F.CrtYd")
		)
		(fp_rect
			(start -0.508 0.9398)
			(end 0.508 -0.9398)
			(stroke
				(width 0)
				(type default)
			)
			(fill no)
			(layer "F.Fab")
		)
		(pad "1" smd custom
			(at 0 -0.4445 180)
			(size 0.1397 0.1397)
			(layers "F.Cu" "F.Mask" "F.Paste")
			(net "AGND_P3V3_STBY")
			(options
				(clearance outline)
				(anchor circle)
			)
			(primitives
				(gr_poly
					(pts
						(arc
							(start -0.1778 -0.2794)
							(mid -0.249642 -0.249642)
							(end -0.2794 -0.1778)
						)
						(arc
							(start -0.2794 0.1778)
							(mid -0.249642 0.249642)
							(end -0.1778 0.2794)
						)
						(arc
							(start 0.1778 0.2794)
							(mid 0.249642 0.249642)
							(end 0.2794 0.1778)
						)
						(arc
							(start 0.2794 -0.1778)
							(mid 0.249642 -0.249642)
							(end 0.1778 -0.2794)
						)
					)
					(width 0)
					(fill yes)
				)
			)
		)
		(pad "2" smd custom
			(at 0 0.4445 180)
			(size 0.1397 0.1397)
			(layers "F.Cu" "F.Mask" "F.Paste")
			(net "P3V3_STBY_RF")
			(options
				(clearance outline)
				(anchor circle)
			)
			(primitives
				(gr_poly
					(pts
						(arc
							(start -0.1778 -0.2794)
							(mid -0.249642 -0.249642)
							(end -0.2794 -0.1778)
						)
						(arc
							(start -0.2794 0.1778)
							(mid -0.249642 0.249642)
							(end -0.1778 0.2794)
						)
						(arc
							(start 0.1778 0.2794)
							(mid 0.249642 0.249642)
							(end 0.2794 0.1778)
						)
						(arc
							(start 0.2794 -0.1778)
							(mid 0.249642 -0.249642)
							(end 0.1778 -0.2794)
						)
					)
					(width 0)
					(fill yes)
				)
			)
		)
	)
	(footprint ""
		(layer "F.Cu")
		(at 134.389622 -8.14959 -90)
		(property "Reference" "Q5"
			(at 0 0 270)
			(layer "F.SilkS")
			(hide yes)
			(effects
				(font
					(size 1.27 1.27)
				)
			)
		)
		(property "Value" "PSMN0R9-25YLC-GP"
			(at -4.2799 -0.4572 270)
			(unlocked yes)
			(layer "F.Fab")
			(hide yes)
			(effects
				(font
					(size 1.016 1.016)
					(thickness 0.1524)
				)
			)
		)
		(property "Device Type" "LFPAK-5PH48-U"
			(at -4.2799 -1.9812 270)
			(unlocked yes)
			(layer "F.Fab")
			(hide yes)
			(effects
				(font
					(size 1.016 1.016)
					(thickness 0.1524)
				)
			)
		)
		(duplicate_pad_numbers_are_jumpers no)
		(fp_line
			(start -1.7272 1.1684)
			(end -2.1082 1.1684)
			(stroke
				(width 0.3302)
				(type default)
			)
			(layer "F.SilkS")
		)
		(fp_line
			(start -2.7559 1.0668)
			(end 2.7559 1.0668)
			(stroke
				(width 0.1524)
				(type default)
			)
			(layer "F.SilkS")
		)
		(fp_line
			(start 2.7559 1.0668)
			(end 2.7559 -6.5532)
			(stroke
				(width 0.1524)
				(type default)
			)
			(layer "F.SilkS")
		)
		(fp_line
			(start -2.7559 -6.5532)
			(end -2.7559 1.0668)
			(stroke
				(width 0.1524)
				(type default)
			)
			(layer "F.SilkS")
		)
		(fp_line
			(start 2.7559 -6.5532)
			(end -2.7559 -6.5532)
			(stroke
				(width 0.1524)
				(type default)
			)
			(layer "F.SilkS")
		)
		(fp_poly
			(pts
				(xy -2.3368 1.5748) (xy -1.905 1.143) (xy -1.4732 1.5748)
			)
			(stroke
				(width 0)
				(type default)
			)
			(fill yes)
			(layer "F.SilkS")
		)
		(fp_poly
			(pts
				(xy -2.5019 -1.09601) (xy -0.3302 -1.09601) (xy -0.3302 -3.36931) (xy -2.5019 -3.36931)
			)
			(stroke
				(width 0)
				(type default)
			)
			(fill yes)
			(layer "F.Paste")
		)
		(fp_poly
			(pts
				(xy 0.3302 -1.09601) (xy 2.5019 -1.09601) (xy 2.5019 -3.36931) (xy 0.3302 -3.36931)
			)
			(stroke
				(width 0)
				(type default)
			)
			(fill yes)
			(layer "F.Paste")
		)
		(fp_poly
			(pts
				(xy -2.5019 -4.02971) (xy -0.3302 -4.02971) (xy -0.3302 -6.30301) (xy -2.5019 -6.30301)
			)
			(stroke
				(width 0)
				(type default)
			)
			(fill yes)
			(layer "F.Paste")
		)
		(fp_poly
			(pts
				(xy 0.3302 -4.02971) (xy 2.5019 -4.02971) (xy 2.5019 -6.30301) (xy 0.3302 -6.30301)
			)
			(stroke
				(width 0)
				(type default)
			)
			(fill yes)
			(layer "F.Paste")
		)
		(fp_rect
			(start -2.4511 0.3048)
			(end 2.4511 -5.6896)
			(stroke
				(width 0)
				(type default)
			)
			(fill no)
			(layer "F.CrtYd")
		)
		(fp_poly
			(pts
				(xy -3.0099 1.3208) (xy -3.0099 -6.8072) (xy 3.0099 -6.8072) (xy 3.0099 -1.016) (xy 2.4511 -1.016)
				(xy 2.4511 -5.6896) (xy -2.4511 -5.6896) (xy -2.4511 0.3048) (xy 2.4511 0.3048) (xy 2.4511 -1.0033)
				(xy 3.0099 -1.0033) (xy 3.0099 1.3208)
			)
			(stroke
				(width 0)
				(type default)
			)
			(fill no)
			(layer "F.CrtYd")
		)
		(fp_rect
			(start -3.0099 1.3208)
			(end 3.0099 -6.8072)
			(stroke
				(width 0)
				(type default)
			)
			(fill no)
			(layer "F.Fab")
		)
		(pad "1" smd rect
			(at -1.905 0 270)
			(size 0.762 1.6256)
			(layers "F.Cu" "F.Mask" "F.Paste")
			(net "P12V_STBY")
		)
		(pad "2" smd rect
			(at -0.635 0 270)
			(size 0.762 1.6256)
			(layers "F.Cu" "F.Mask" "F.Paste")
			(net "P12V_STBY")
		)
		(pad "3" smd rect
			(at 0.635 0 270)
			(size 0.762 1.6256)
			(layers "F.Cu" "F.Mask" "F.Paste")
			(net "P12V_STBY")
		)
		(pad "4" smd rect
			(at 1.905 0 270)
			(size 0.762 1.6256)
			(layers "F.Cu" "F.Mask" "F.Paste")
			(net "MB0_12V_CTRL_GATE1")
		)
		(pad "5" smd rect
			(at 0 -3.69951 270)
			(size 5.0038 5.207)
			(layers "F.Cu" "F.Mask" "F.Paste")
			(net "MB0_P12V_MAIN_R")
		)
	)
	(footprint ""
		(layer "F.Cu")
		(at 77.18298 -155.5369 -90)
		(property "Reference" "C234"
			(at 0 0 270)
			(layer "F.SilkS")
			(hide yes)
			(effects
				(font
					(size 1.27 1.27)
				)
			)
		)
		(property "Value" "SC1KP50V2KX-1GP"
			(at 1.1811 -2.7051 270)
			(unlocked yes)
			(layer "F.Fab")
			(hide yes)
			(effects
				(font
					(size 1.016 1.016)
					(thickness 0.1524)
				)
			)
		)
		(property "Device Type" "C402H22"
			(at 1.1811 -4.2291 270)
			(unlocked yes)
			(layer "F.Fab")
			(hide yes)
			(effects
				(font
					(size 1.016 1.016)
					(thickness 0.1524)
				)
			)
		)
		(duplicate_pad_numbers_are_jumpers no)
		(fp_rect
			(start -0.4318 0.9525)
			(end 0.4318 -0.9525)
			(stroke
				(width 0)
				(type default)
			)
			(fill no)
			(layer "F.CrtYd")
		)
		(fp_rect
			(start -0.4318 0.9525)
			(end 0.4318 -0.9525)
			(stroke
				(width 0)
				(type default)
			)
			(fill no)
			(layer "F.Fab")
		)
		(pad "1" smd custom
			(at 0 -0.4445 270)
			(size 0.1524 0.1524)
			(layers "F.Cu" "F.Mask" "F.Paste")
			(net "TPS74801_P1V15_STBY_OUT")
			(options
				(clearance outline)
				(anchor circle)
			)
			(primitives
				(gr_poly
					(pts
						(arc
							(start 0.3048 -0.2032)
							(mid 0.275042 -0.275042)
							(end 0.2032 -0.3048)
						)
						(arc
							(start -0.2032 -0.3048)
							(mid -0.275042 -0.275042)
							(end -0.3048 -0.2032)
						)
						(arc
							(start -0.3048 0.2032)
							(mid -0.275042 0.275042)
							(end -0.2032 0.3048)
						)
						(arc
							(start 0.2032 0.3048)
							(mid 0.275042 0.275042)
							(end 0.3048 0.2032)
						)
					)
					(width 0)
					(fill yes)
				)
			)
		)
		(pad "2" smd custom
			(at 0 0.4445 270)
			(size 0.1524 0.1524)
			(layers "F.Cu" "F.Mask" "F.Paste")
			(net "TPS74801_P1V15_STBY_FB")
			(options
				(clearance outline)
				(anchor circle)
			)
			(primitives
				(gr_poly
					(pts
						(arc
							(start 0.3048 -0.2032)
							(mid 0.275042 -0.275042)
							(end 0.2032 -0.3048)
						)
						(arc
							(start -0.2032 -0.3048)
							(mid -0.275042 -0.275042)
							(end -0.3048 -0.2032)
						)
						(arc
							(start -0.3048 0.2032)
							(mid -0.275042 0.275042)
							(end -0.2032 0.3048)
						)
						(arc
							(start 0.2032 0.3048)
							(mid 0.275042 0.275042)
							(end 0.3048 0.2032)
						)
					)
					(width 0)
					(fill yes)
				)
			)
		)
	)
	(footprint ""
		(layer "F.Cu")
		(at 174.560738 -70.49262 90)
		(property "Reference" "R580"
			(at 0 0 90)
			(layer "F.SilkS")
			(hide yes)
			(effects
				(font
					(size 1.27 1.27)
				)
			)
		)
		(property "Value" "2K2R2F-GP"
			(at 0.064008 -3.993896 90)
			(unlocked yes)
			(layer "F.Fab")
			(hide yes)
			(effects
				(font
					(size 1.016 1.016)
					(thickness 0.1524)
				)
			)
		)
		(property "Device Type" "R402H16"
			(at 0.064008 -5.517896 90)
			(unlocked yes)
			(layer "F.Fab")
			(hide yes)
			(effects
				(font
					(size 1.016 1.016)
					(thickness 0.1524)
				)
			)
		)
		(duplicate_pad_numbers_are_jumpers no)
		(fp_line
			(start 0.508 -0.9398)
			(end -0.508 -0.9398)
			(stroke
				(width 0.1524)
				(type default)
			)
			(layer "F.SilkS")
		)
		(fp_line
			(start -0.508 -0.9398)
			(end -0.508 0.9398)
			(stroke
				(width 0.1524)
				(type default)
			)
			(layer "F.SilkS")
		)
		(fp_rect
			(start -0.508 0.9398)
			(end 0.508 -0.9398)
			(stroke
				(width 0)
				(type default)
			)
			(fill no)
			(layer "F.CrtYd")
		)
		(fp_rect
			(start -0.508 0.9398)
			(end 0.508 -0.9398)
			(stroke
				(width 0)
				(type default)
			)
			(fill no)
			(layer "F.Fab")
		)
		(pad "1" smd custom
			(at 0 -0.4445 90)
			(size 0.1397 0.1397)
			(layers "F.Cu" "F.Mask" "F.Paste")
			(net "P1V8")
			(options
				(clearance outline)
				(anchor circle)
			)
			(primitives
				(gr_poly
					(pts
						(arc
							(start -0.1778 -0.2794)
							(mid -0.249642 -0.249642)
							(end -0.2794 -0.1778)
						)
						(arc
							(start -0.2794 0.1778)
							(mid -0.249642 0.249642)
							(end -0.1778 0.2794)
						)
						(arc
							(start 0.1778 0.2794)
							(mid 0.249642 0.249642)
							(end 0.2794 0.1778)
						)
						(arc
							(start 0.2794 -0.1778)
							(mid 0.249642 -0.249642)
							(end 0.1778 -0.2794)
						)
					)
					(width 0)
					(fill yes)
				)
			)
		)
		(pad "2" smd custom
			(at 0 0.4445 90)
			(size 0.1397 0.1397)
			(layers "F.Cu" "F.Mask" "F.Paste")
			(net "IOC_SCL_0")
			(options
				(clearance outline)
				(anchor circle)
			)
			(primitives
				(gr_poly
					(pts
						(arc
							(start -0.1778 -0.2794)
							(mid -0.249642 -0.249642)
							(end -0.2794 -0.1778)
						)
						(arc
							(start -0.2794 0.1778)
							(mid -0.249642 0.249642)
							(end -0.1778 0.2794)
						)
						(arc
							(start 0.1778 0.2794)
							(mid 0.249642 0.249642)
							(end 0.2794 0.1778)
						)
						(arc
							(start 0.2794 -0.1778)
							(mid 0.249642 -0.249642)
							(end 0.1778 -0.2794)
						)
					)
					(width 0)
					(fill yes)
				)
			)
		)
	)
	(footprint ""
		(layer "F.Cu")
		(at 77.1398 -156.561536 -90)
		(property "Reference" "R537"
			(at 0 0 270)
			(layer "F.SilkS")
			(hide yes)
			(effects
				(font
					(size 1.27 1.27)
				)
			)
		)
		(property "Value" "2K05R2F-1-GP"
			(at 0.064008 -3.993896 270)
			(unlocked yes)
			(layer "F.Fab")
			(hide yes)
			(effects
				(font
					(size 1.016 1.016)
					(thickness 0.1524)
				)
			)
		)
		(property "Device Type" "R402H16"
			(at 0.064008 -5.517896 270)
			(unlocked yes)
			(layer "F.Fab")
			(hide yes)
			(effects
				(font
					(size 1.016 1.016)
					(thickness 0.1524)
				)
			)
		)
		(duplicate_pad_numbers_are_jumpers no)
		(fp_line
			(start -0.508 -0.9398)
			(end -0.508 0.9398)
			(stroke
				(width 0.1524)
				(type default)
			)
			(layer "F.SilkS")
		)
		(fp_line
			(start 0.508 -0.9398)
			(end -0.508 -0.9398)
			(stroke
				(width 0.1524)
				(type default)
			)
			(layer "F.SilkS")
		)
		(fp_rect
			(start -0.508 0.9398)
			(end 0.508 -0.9398)
			(stroke
				(width 0)
				(type default)
			)
			(fill no)
			(layer "F.CrtYd")
		)
		(fp_rect
			(start -0.508 0.9398)
			(end 0.508 -0.9398)
			(stroke
				(width 0)
				(type default)
			)
			(fill no)
			(layer "F.Fab")
		)
		(pad "1" smd custom
			(at 0 -0.4445 270)
			(size 0.1397 0.1397)
			(layers "F.Cu" "F.Mask" "F.Paste")
			(net "TPS74801_P1V15_STBY_OUT")
			(options
				(clearance outline)
				(anchor circle)
			)
			(primitives
				(gr_poly
					(pts
						(arc
							(start -0.1778 -0.2794)
							(mid -0.249642 -0.249642)
							(end -0.2794 -0.1778)
						)
						(arc
							(start -0.2794 0.1778)
							(mid -0.249642 0.249642)
							(end -0.1778 0.2794)
						)
						(arc
							(start 0.1778 0.2794)
							(mid 0.249642 0.249642)
							(end 0.2794 0.1778)
						)
						(arc
							(start 0.2794 -0.1778)
							(mid 0.249642 -0.249642)
							(end 0.1778 -0.2794)
						)
					)
					(width 0)
					(fill yes)
				)
			)
		)
		(pad "2" smd custom
			(at 0 0.4445 270)
			(size 0.1397 0.1397)
			(layers "F.Cu" "F.Mask" "F.Paste")
			(net "TPS74801_P1V15_STBY_FB")
			(options
				(clearance outline)
				(anchor circle)
			)
			(primitives
				(gr_poly
					(pts
						(arc
							(start -0.1778 -0.2794)
							(mid -0.249642 -0.249642)
							(end -0.2794 -0.1778)
						)
						(arc
							(start -0.2794 0.1778)
							(mid -0.249642 0.249642)
							(end -0.1778 0.2794)
						)
						(arc
							(start 0.1778 0.2794)
							(mid 0.249642 0.249642)
							(end 0.2794 0.1778)
						)
						(arc
							(start 0.2794 -0.1778)
							(mid 0.249642 -0.249642)
							(end 0.1778 -0.2794)
						)
					)
					(width 0)
					(fill yes)
				)
			)
		)
	)
	(footprint ""
		(layer "F.Cu")
		(at 74.442828 -175.754538 90)
		(property "Reference" "R506"
			(at 0 0 90)
			(layer "F.SilkS")
			(hide yes)
			(effects
				(font
					(size 1.27 1.27)
				)
			)
		)
		(property "Value" "1K69R2F-2-GP"
			(at 0.064008 -3.993896 90)
			(unlocked yes)
			(layer "F.Fab")
			(hide yes)
			(effects
				(font
					(size 1.016 1.016)
					(thickness 0.1524)
				)
			)
		)
		(property "Device Type" "R402H16"
			(at 0.064008 -5.517896 90)
			(unlocked yes)
			(layer "F.Fab")
			(hide yes)
			(effects
				(font
					(size 1.016 1.016)
					(thickness 0.1524)
				)
			)
		)
		(duplicate_pad_numbers_are_jumpers no)
		(fp_line
			(start 0.508 -0.9398)
			(end -0.508 -0.9398)
			(stroke
				(width 0.1524)
				(type default)
			)
			(layer "F.SilkS")
		)
		(fp_line
			(start -0.508 -0.9398)
			(end -0.508 0.9398)
			(stroke
				(width 0.1524)
				(type default)
			)
			(layer "F.SilkS")
		)
		(fp_rect
			(start -0.508 0.9398)
			(end 0.508 -0.9398)
			(stroke
				(width 0)
				(type default)
			)
			(fill no)
			(layer "F.CrtYd")
		)
		(fp_rect
			(start -0.508 0.9398)
			(end 0.508 -0.9398)
			(stroke
				(width 0)
				(type default)
			)
			(fill no)
			(layer "F.Fab")
		)
		(pad "1" smd custom
			(at 0 -0.4445 90)
			(size 0.1397 0.1397)
			(layers "F.Cu" "F.Mask" "F.Paste")
			(net "TPS74801_P2V5_STBY_FB")
			(options
				(clearance outline)
				(anchor circle)
			)
			(primitives
				(gr_poly
					(pts
						(arc
							(start -0.1778 -0.2794)
							(mid -0.249642 -0.249642)
							(end -0.2794 -0.1778)
						)
						(arc
							(start -0.2794 0.1778)
							(mid -0.249642 0.249642)
							(end -0.1778 0.2794)
						)
						(arc
							(start 0.1778 0.2794)
							(mid 0.249642 0.249642)
							(end 0.2794 0.1778)
						)
						(arc
							(start 0.2794 -0.1778)
							(mid 0.249642 -0.249642)
							(end 0.1778 -0.2794)
						)
					)
					(width 0)
					(fill yes)
				)
			)
		)
		(pad "2" smd custom
			(at 0 0.4445 90)
			(size 0.1397 0.1397)
			(layers "F.Cu" "F.Mask" "F.Paste")
			(net "GND")
			(options
				(clearance outline)
				(anchor circle)
			)
			(primitives
				(gr_poly
					(pts
						(arc
							(start -0.1778 -0.2794)
							(mid -0.249642 -0.249642)
							(end -0.2794 -0.1778)
						)
						(arc
							(start -0.2794 0.1778)
							(mid -0.249642 0.249642)
							(end -0.1778 0.2794)
						)
						(arc
							(start 0.1778 0.2794)
							(mid 0.249642 0.249642)
							(end 0.2794 0.1778)
						)
						(arc
							(start 0.2794 -0.1778)
							(mid 0.249642 -0.249642)
							(end 0.1778 -0.2794)
						)
					)
					(width 0)
					(fill yes)
				)
			)
		)
	)
	(footprint ""
		(layer "F.Cu")
		(at 160.9852 -86.2838)
		(property "Reference" "C481"
			(at 0 0 0)
			(layer "F.SilkS")
			(hide yes)
			(effects
				(font
					(size 1.27 1.27)
				)
			)
		)
		(property "Value" "SCD1U16V2KX-3GP"
			(at 1.1811 -2.7051 0)
			(unlocked yes)
			(layer "F.Fab")
			(hide yes)
			(effects
				(font
					(size 1.016 1.016)
					(thickness 0.1524)
				)
			)
		)
		(property "Device Type" "C402H22"
			(at 1.1811 -4.2291 0)
			(unlocked yes)
			(layer "F.Fab")
			(hide yes)
			(effects
				(font
					(size 1.016 1.016)
					(thickness 0.1524)
				)
			)
		)
		(duplicate_pad_numbers_are_jumpers no)
		(fp_rect
			(start -0.4318 0.9525)
			(end 0.4318 -0.9525)
			(stroke
				(width 0)
				(type default)
			)
			(fill no)
			(layer "F.CrtYd")
		)
		(fp_rect
			(start -0.4318 0.9525)
			(end 0.4318 -0.9525)
			(stroke
				(width 0)
				(type default)
			)
			(fill no)
			(layer "F.Fab")
		)
		(pad "1" smd custom
			(at 0 -0.4445)
			(size 0.1524 0.1524)
			(layers "F.Cu" "F.Mask" "F.Paste")
			(net "P1V8")
			(options
				(clearance outline)
				(anchor circle)
			)
			(primitives
				(gr_poly
					(pts
						(arc
							(start 0.3048 -0.2032)
							(mid 0.275042 -0.275042)
							(end 0.2032 -0.3048)
						)
						(arc
							(start -0.2032 -0.3048)
							(mid -0.275042 -0.275042)
							(end -0.3048 -0.2032)
						)
						(arc
							(start -0.3048 0.2032)
							(mid -0.275042 0.275042)
							(end -0.2032 0.3048)
						)
						(arc
							(start 0.2032 0.3048)
							(mid 0.275042 0.275042)
							(end 0.3048 0.2032)
						)
					)
					(width 0)
					(fill yes)
				)
			)
		)
		(pad "2" smd custom
			(at 0 0.4445)
			(size 0.1524 0.1524)
			(layers "F.Cu" "F.Mask" "F.Paste")
			(net "GND")
			(options
				(clearance outline)
				(anchor circle)
			)
			(primitives
				(gr_poly
					(pts
						(arc
							(start 0.3048 -0.2032)
							(mid 0.275042 -0.275042)
							(end 0.2032 -0.3048)
						)
						(arc
							(start -0.2032 -0.3048)
							(mid -0.275042 -0.275042)
							(end -0.3048 -0.2032)
						)
						(arc
							(start -0.3048 0.2032)
							(mid -0.275042 0.275042)
							(end -0.2032 0.3048)
						)
						(arc
							(start 0.2032 0.3048)
							(mid 0.275042 0.275042)
							(end 0.3048 0.2032)
						)
					)
					(width 0)
					(fill yes)
				)
			)
		)
	)
)
